(kicad_pcb
	(version 20221018)
	(generator pcbnew)
	(general
    (thickness 1.7403)
  )
	(paper "A4")
	(title_block
    (title "Data Center RDIMM DDR4 Tester")
    (date "2024-09-30")
    (rev "1.2.4")
		(comment 9 "footprints 302-310 of 690")
	)
	(layers
    (0 "F.Cu" signal)
    (1 "In1.Cu" power)
    (2 "In2.Cu" signal)
    (3 "In3.Cu" power)
    (4 "In4.Cu" power)
    (5 "In5.Cu" signal)
    (6 "In6.Cu" power)
    (7 "In7.Cu" signal)
    (8 "In8.Cu" power)
    (9 "In9.Cu" signal)
    (10 "In10.Cu" power)
    (31 "B.Cu" signal)
    (32 "B.Adhes" user "B.Adhesive")
    (33 "F.Adhes" user "F.Adhesive")
    (34 "B.Paste" user)
    (35 "F.Paste" user)
    (36 "B.SilkS" user "B.Silkscreen")
    (37 "F.SilkS" user "F.Silkscreen")
    (38 "B.Mask" user)
    (39 "F.Mask" user)
    (40 "Dwgs.User" user "User.Drawings")
    (41 "Cmts.User" user "User.Comments")
    (42 "Eco1.User" user "User.Eco1")
    (43 "Eco2.User" user "User.Eco2")
    (44 "Edge.Cuts" user)
    (45 "Margin" user)
    (46 "B.CrtYd" user "B.Courtyard")
    (47 "F.CrtYd" user "F.Courtyard")
    (48 "B.Fab" user)
    (49 "F.Fab" user)
  )
	(footprint "data-center-rdimm-ddr4-tester-footprints:R_0402_1005Metric" (layer "F.Cu")
    (at 250.9 120.815 180)
    (descr "Resistor SMD 0402")
    (tags "resistor SMD 0402")
    (property "Author" "Antmicro")
    (property "License" "Apache-2.0")
    (property "MPN" "CR0402-FX-33R0GLF")
    (property "Manufacturer" "Bourns")
    (property "Sheetfile" "fmc_hpc.kicad_sch")
    (property "Sheetname" "FMC HPC")
    (property "Tolerance" "1%")
    (property "Val" "33R")
    (property "ki_description" "33R resistor in 0402 package with 1% tolerance")
    (attr smd)
    (fp_text reference "R210" (at 1.03 1.565 180) (layer "F.SilkS")
        (effects (font (size 0.7 0.7) (thickness 0.15)) (justify left bottom))
    )
    (fp_text value "R_33R_0402" (at 0 1.4 180) (layer "F.Fab") hide
        (effects (font (size 0.7 0.7) (thickness 0.15)) (justify left bottom))
    )
    (fp_text user "${REFERENCE}" (at -0.95 3.168 180) (layer "F.Fab") hide
        (effects (font (size 0.7 0.7) (thickness 0.15)) (justify left bottom))
    )
    (fp_text user "Author: Antmicro" (at -0.95 4.169 180) (layer "F.Fab") hide
        (effects (font (size 0.7 0.7) (thickness 0.15)) (justify left bottom))
    )
    (fp_text user "License: Apache-2.0" (at -0.95 5.169 180) (layer "F.Fab") hide
        (effects (font (size 0.7 0.7) (thickness 0.15)) (justify left bottom))
    )
    (fp_rect (start -0.93 -0.47) (end 0.93 0.47)
      (stroke (width 0.05) (type solid)) (fill none) (layer "F.CrtYd"))
    (fp_rect (start -0.5 -0.25) (end 0.5 0.25)
      (stroke (width 0.15) (type solid)) (fill none) (layer "F.Fab"))
    (pad "1" smd roundrect (at -0.485 0 180) (size 0.59 0.64) (layers "F.Cu" "F.Paste" "F.Mask") (roundrect_rratio 0.25)
      (net 668 "/FMC HPC/GTR_REFCLK0_R_P") (pintype "passive"))
    (pad "2" smd roundrect (at 0.485 0 180) (size 0.59 0.64) (layers "F.Cu" "F.Paste" "F.Mask") (roundrect_rratio 0.25)
      (net 403 "GTR_REFCLK0_C_P") (pintype "passive"))
  )
	(footprint "data-center-rdimm-ddr4-tester-footprints:SW_1-1825027-1_THT" (layer "F.Cu")
    (at 234.156 131.6725)
    (descr "Tactile Switches, Round Actuator Style, NO, 5.74mm")
    (property "Author" "Antmicro")
    (property "License" "Apache-2.0")
    (property "MPN" "1-1825027-1")
    (property "Manufacturer" "TE Connectivity")
    (property "Sheetfile" "supply.kicad_sch")
    (property "Sheetname" "Supply")
    (property "ki_description" "Tactile Switch, Side Actuated, Through Hole, Round Button, 160 gf, 50mA at 24VDC")
    (property "ki_keywords" "HORIZONTAL, SWITCH, THT, MECHANICAL, TACTILE")
    (attr through_hole)
    (fp_text reference "S3" (at 7.144 2.9475 90) (layer "F.SilkS")
        (effects (font (size 0.7 0.7) (thickness 0.15)) (justify left bottom))
    )
    (fp_text value "SW_1-1825027-1" (at -2.4 9.6) (layer "F.Fab")
        (effects (font (size 0.7 0.7) (thickness 0.15)) (justify left bottom))
    )
    (fp_text user "${REFERENCE}" (at -2.452 11) (layer "F.Fab") hide
        (effects (font (size 0.7 0.7) (thickness 0.15)) (justify left bottom))
    )
    (fp_text user "Author: Antmicro" (at -2.452 12.4) (layer "F.Fab") hide
        (effects (font (size 0.7 0.7) (thickness 0.15)) (justify left bottom))
    )
    (fp_text user "License: Apache-2.0" (at -2.452 13.88) (layer "F.Fab") hide
        (effects (font (size 0.7 0.7) (thickness 0.15)) (justify left bottom))
    )
    (fp_line (start -1.331 -4.01) (end 5.828 -4.01)
      (stroke (width 0.15) (type solid)) (layer "F.SilkS"))
    (fp_line (start -1.307 2.548) (end -1.307 -0.485)
      (stroke (width 0.15) (type solid)) (layer "F.SilkS"))
    (fp_line (start 4.004 2.6) (end 0.494 2.6)
      (stroke (width 0.15) (type solid)) (layer "F.SilkS"))
    (fp_line (start 5.804 -0.5) (end 5.799 2.6)
      (stroke (width 0.15) (type solid)) (layer "F.SilkS"))
    (fp_line (start -1.6 -4.21) (end -1.6 2.89)
      (stroke (width 0.05) (type solid)) (layer "F.CrtYd"))
    (fp_line (start -1.6 2.89) (end 0.14 2.89)
      (stroke (width 0.05) (type solid)) (layer "F.CrtYd"))
    (fp_line (start 0.14 2.89) (end 0.14 8.58)
      (stroke (width 0.05) (type solid)) (layer "F.CrtYd"))
    (fp_line (start 0.14 8.58) (end 4.24 8.58)
      (stroke (width 0.05) (type solid)) (layer "F.CrtYd"))
    (fp_line (start 4.24 2.89) (end 6.1 2.89)
      (stroke (width 0.05) (type solid)) (layer "F.CrtYd"))
    (fp_line (start 4.24 8.58) (end 4.24 2.89)
      (stroke (width 0.05) (type solid)) (layer "F.CrtYd"))
    (fp_line (start 6.1 -4.21) (end -1.6 -4.21)
      (stroke (width 0.05) (type solid)) (layer "F.CrtYd"))
    (fp_line (start 6.1 2.89) (end 6.1 -4.21)
      (stroke (width 0.05) (type solid)) (layer "F.CrtYd"))
    (fp_line (start -1.307 -4.01) (end 5.804 -4.01)
      (stroke (width 0.15) (type solid)) (layer "F.Fab"))
    (fp_line (start -1.307 2.6) (end -1.307 -4.01)
      (stroke (width 0.15) (type solid)) (layer "F.Fab"))
    (fp_line (start 0.494 2.6) (end -1.307 2.6)
      (stroke (width 0.15) (type solid)) (layer "F.Fab"))
    (fp_line (start 0.494 2.6) (end 0.494 8.349)
      (stroke (width 0.15) (type solid)) (layer "F.Fab"))
    (fp_line (start 0.494 8.349) (end 4.004 8.349)
      (stroke (width 0.15) (type solid)) (layer "F.Fab"))
    (fp_line (start 4.004 8.349) (end 3.999 2.6)
      (stroke (width 0.15) (type solid)) (layer "F.Fab"))
    (fp_line (start 5.799 2.6) (end 3.999 2.6)
      (stroke (width 0.15) (type solid)) (layer "F.Fab"))
    (fp_line (start 5.804 -4.01) (end 5.804 2.6)
      (stroke (width 0.15) (type solid)) (layer "F.Fab"))
    (pad "1" thru_hole circle (at 0 0) (size 1.498 1.498) (drill 0.99) (layers "*.Cu" "*.Mask")
      (net 664 "Net-(U26-~{PB_IN})") (pinfunction "1") (pintype "passive"))
    (pad "2" thru_hole circle (at 4.498 0) (size 1.498 1.498) (drill 0.99) (layers "*.Cu" "*.Mask")
      (net 9 "GND") (pinfunction "2") (pintype "passive"))
    (pad "SH" thru_hole circle (at -1.256 -2.492) (size 1.95 1.95) (drill 1.3) (layers "*.Cu" "*.Mask")
      (net 9 "GND") (pinfunction "SH") (pintype "passive"))
    (pad "SH" thru_hole circle (at 5.754 -2.492) (size 1.95 1.95) (drill 1.3) (layers "*.Cu" "*.Mask")
      (net 9 "GND") (pinfunction "SH") (pintype "passive"))
  )
	(footprint "data-center-rdimm-ddr4-tester-footprints:C_0402_1005Metric" (layer "F.Cu")
    (at 115.975 96.6 180)
    (descr "Capacitor SMD 0402")
    (tags "capacitor SMD 0402")
    (property "Author" "Antmicro")
    (property "Dielectric" "")
    (property "License" "Apache-2.0")
    (property "MPN" "CC0402MRX5R5BB106")
    (property "Manufacturer" "Yaego")
    (property "Sheetfile" "supply.kicad_sch")
    (property "Sheetname" "Supply")
    (property "Val" "10u")
    (property "Voltage" "")
    (property "ki_description" " ")
    (attr smd)
    (fp_text reference "C33" (at 1.065 0.53 180) (layer "F.SilkS")
        (effects (font (size 0.7 0.7) (thickness 0.15)) (justify left bottom))
    )
    (fp_text value "C_10u_0402" (at 0 1.4 180) (layer "F.Fab") hide
        (effects (font (size 0.7 0.7) (thickness 0.15)) (justify left bottom))
    )
    (fp_text user "License: Apache-2.0" (at -0.932 5.17 180) (layer "F.Fab") hide
        (effects (font (size 0.7 0.7) (thickness 0.15)) (justify left bottom))
    )
    (fp_text user "Author: Antmicro" (at -0.932 4.17 180) (layer "F.Fab") hide
        (effects (font (size 0.7 0.7) (thickness 0.15)) (justify left bottom))
    )
    (fp_text user "${REFERENCE}" (at -0.932 3.168 180) (layer "F.Fab") hide
        (effects (font (size 0.7 0.7) (thickness 0.15)) (justify left bottom))
    )
    (fp_rect (start -0.94 -0.47) (end 0.94 0.47)
      (stroke (width 0.05) (type solid)) (fill none) (layer "F.CrtYd"))
    (fp_rect (start -0.499 -0.249) (end 0.499 0.249)
      (stroke (width 0.15) (type solid)) (fill none) (layer "F.Fab"))
    (pad "1" smd roundrect (at -0.484 0 180) (size 0.59 0.64) (layers "F.Cu" "F.Paste" "F.Mask") (roundrect_rratio 0.25)
      (net 301 "VDD1V2") (pintype "passive"))
    (pad "2" smd roundrect (at 0.484 0 180) (size 0.59 0.64) (layers "F.Cu" "F.Paste" "F.Mask") (roundrect_rratio 0.25)
      (net 9 "GND") (pintype "passive"))
  )
	(footprint "data-center-rdimm-ddr4-tester-footprints:NetTie-2_SMD_Pad0.127mm" (layer "F.Cu")
    (at 131.6 98.633 90)
    (descr "Net tie, 2 pin, 0.127mm  SMD pads")
    (tags "net tie")
    (property "Author" "Antmicro")
    (property "License" "Apache-2.0")
    (property "MPN" "")
    (property "Manufacturer" "")
    (property "Sheetfile" "supply.kicad_sch")
    (property "Sheetname" "Supply")
    (property "ki_description" "Net tie, 2 pins")
    (property "ki_keywords" "net tie short")
    (attr through_hole exclude_from_pos_files)
    (net_tie_pad_groups "1, 2")
    (fp_text reference "NT11" (at -0.128 -1.345 90) (layer "F.SilkS") hide
        (effects (font (size 0.7 0.7) (thickness 0.15)) (justify left bottom))
    )
    (fp_text value "Net-Tie_2" (at 0 1.199 90) (layer "F.Fab") hide
        (effects (font (size 0.7 0.7) (thickness 0.15)) (justify left bottom))
    )
    (fp_text user "${REFERENCE}" (at -0.128 3.2 90) (layer "F.Fab") hide
        (effects (font (size 0.7 0.7) (thickness 0.15)) (justify left bottom))
    )
    (fp_text user "Author: Antmicro" (at -0.128 4.4 90) (layer "F.Fab") hide
        (effects (font (size 0.7 0.7) (thickness 0.15)) (justify left bottom))
    )
    (fp_text user "License: Apache-2.0" (at -0.128 5.6 90) (layer "F.Fab") hide
        (effects (font (size 0.7 0.7) (thickness 0.15)) (justify left bottom))
    )
    (fp_poly
      (pts
        (xy -0.0635 -0.0635)
        (xy 0.0625 -0.0635)
        (xy 0.0625 0.0635)
        (xy -0.0635 0.0635)
      )

      (stroke (width 0) (type solid)) (fill solid) (layer "F.Cu"))
    (pad "1" smd roundrect (at -0.127 0 270) (size 0.127 0.127) (layers "F.Cu") (roundrect_rratio 0.5)
      (chamfer_ratio 0) (chamfer top_left bottom_left)
      (net 842 "/Supply/5V0_SEN_-") (pinfunction "1") (pintype "passive"))
    (pad "2" smd roundrect (at 0.126 0 90) (size 0.127 0.127) (layers "F.Cu") (roundrect_rratio 0.5)
      (chamfer_ratio 0) (chamfer top_left bottom_left)
      (net 307 "5V0_SYS") (pinfunction "2") (pintype "passive"))
  )
	(footprint "data-center-rdimm-ddr4-tester-footprints:NetTie-2_SMD_Pad0.127mm" (layer "F.Cu")
    (at 123.2 89.267 -90)
    (descr "Net tie, 2 pin, 0.127mm  SMD pads")
    (tags "net tie")
    (property "Author" "Antmicro")
    (property "License" "Apache-2.0")
    (property "MPN" "")
    (property "Manufacturer" "")
    (property "Sheetfile" "supply.kicad_sch")
    (property "Sheetname" "Supply")
    (property "ki_description" "Net tie, 2 pins")
    (property "ki_keywords" "net tie short")
    (attr through_hole exclude_from_pos_files)
    (net_tie_pad_groups "1, 2")
    (fp_text reference "NT1" (at -0.128 -1.345 -90) (layer "F.SilkS") hide
        (effects (font (size 0.7 0.7) (thickness 0.15)) (justify left bottom))
    )
    (fp_text value "Net-Tie_2" (at 0 1.199 -90) (layer "F.Fab") hide
        (effects (font (size 0.7 0.7) (thickness 0.15)) (justify left bottom))
    )
    (fp_text user "License: Apache-2.0" (at -0.128 5.6 -90) (layer "F.Fab") hide
        (effects (font (size 0.7 0.7) (thickness 0.15)) (justify left bottom))
    )
    (fp_text user "Author: Antmicro" (at -0.128 4.4 -90) (layer "F.Fab") hide
        (effects (font (size 0.7 0.7) (thickness 0.15)) (justify left bottom))
    )
    (fp_text user "${REFERENCE}" (at -0.128 3.2 -90) (layer "F.Fab") hide
        (effects (font (size 0.7 0.7) (thickness 0.15)) (justify left bottom))
    )
    (fp_poly
      (pts
        (xy -0.0635 -0.0635)
        (xy 0.0625 -0.0635)
        (xy 0.0625 0.0635)
        (xy -0.0635 0.0635)
      )

      (stroke (width 0) (type solid)) (fill solid) (layer "F.Cu"))
    (pad "1" smd roundrect (at -0.127 0 90) (size 0.127 0.127) (layers "F.Cu") (roundrect_rratio 0.5)
      (chamfer_ratio 0) (chamfer top_left bottom_left)
      (net 832 "/Supply/VPP_SEN_+") (pinfunction "1") (pintype "passive"))
    (pad "2" smd roundrect (at 0.126 0 270) (size 0.127 0.127) (layers "F.Cu") (roundrect_rratio 0.5)
      (chamfer_ratio 0) (chamfer top_left bottom_left)
      (net 303 "VCC2V5") (pinfunction "2") (pintype "passive"))
  )
	(footprint "data-center-rdimm-ddr4-tester-footprints:C_0402_1005Metric" (layer "F.Cu")
    (at 254.71 81.715 180)
    (descr "Capacitor SMD 0402")
    (tags "capacitor SMD 0402")
    (property "Author" "Antmicro")
    (property "Dielectric" "X5R")
    (property "License" "Apache-2.0")
    (property "MPN" "GRM155R61H104KE14D")
    (property "Manufacturer" "Murata")
    (property "Sheetfile" "fmc_hpc.kicad_sch")
    (property "Sheetname" "FMC HPC")
    (property "Val" "100n")
    (property "Voltage" "50V")
    (property "ki_description" " ")
    (attr smd)
    (fp_text reference "C268" (at -0.78 -0.295 180) (layer "F.SilkS")
        (effects (font (size 0.7 0.7) (thickness 0.15)) (justify left bottom))
    )
    (fp_text value "C_100n_0402" (at 0 1.4 180) (layer "F.Fab") hide
        (effects (font (size 0.7 0.7) (thickness 0.15)) (justify left bottom))
    )
    (fp_text user "${REFERENCE}" (at -0.932 3.168 180) (layer "F.Fab") hide
        (effects (font (size 0.7 0.7) (thickness 0.15)) (justify left bottom))
    )
    (fp_text user "License: Apache-2.0" (at -0.932 5.17 180) (layer "F.Fab") hide
        (effects (font (size 0.7 0.7) (thickness 0.15)) (justify left bottom))
    )
    (fp_text user "Author: Antmicro" (at -0.932 4.17 180) (layer "F.Fab") hide
        (effects (font (size 0.7 0.7) (thickness 0.15)) (justify left bottom))
    )
    (fp_rect (start -0.94 -0.47) (end 0.94 0.47)
      (stroke (width 0.05) (type solid)) (fill none) (layer "F.CrtYd"))
    (fp_rect (start -0.499 -0.249) (end 0.499 0.249)
      (stroke (width 0.15) (type solid)) (fill none) (layer "F.Fab"))
    (pad "1" smd roundrect (at -0.484 0 180) (size 0.59 0.64) (layers "F.Cu" "F.Paste" "F.Mask") (roundrect_rratio 0.25)
      (net 466 "/FMC HPC/GTX_TX4_C_N") (pintype "passive"))
    (pad "2" smd roundrect (at 0.484 0 180) (size 0.59 0.64) (layers "F.Cu" "F.Paste" "F.Mask") (roundrect_rratio 0.25)
      (net 479 "GTX_TX4_N") (pintype "passive"))
  )
	(footprint "data-center-rdimm-ddr4-tester-footprints:C_0402_1005Metric" (layer "F.Cu")
    (at 254.175 120.86)
    (descr "Capacitor SMD 0402")
    (tags "capacitor SMD 0402")
    (property "Author" "Antmicro")
    (property "Dielectric" "X5R")
    (property "License" "Apache-2.0")
    (property "MPN" "GRM155R61H104KE14D")
    (property "Manufacturer" "Murata")
    (property "Sheetfile" "fmc_hpc.kicad_sch")
    (property "Sheetname" "FMC HPC")
    (property "Val" "100n")
    (property "Voltage" "50V")
    (property "ki_description" " ")
    (attr smd)
    (fp_text reference "C260" (at -1.315 -1.58) (layer "F.SilkS")
        (effects (font (size 0.7 0.7) (thickness 0.15)) (justify left bottom))
    )
    (fp_text value "C_100n_0402" (at 0 1.4) (layer "F.Fab") hide
        (effects (font (size 0.7 0.7) (thickness 0.15)) (justify left bottom))
    )
    (fp_text user "${REFERENCE}" (at -0.932 3.168) (layer "F.Fab") hide
        (effects (font (size 0.7 0.7) (thickness 0.15)) (justify left bottom))
    )
    (fp_text user "License: Apache-2.0" (at -0.932 5.17) (layer "F.Fab") hide
        (effects (font (size 0.7 0.7) (thickness 0.15)) (justify left bottom))
    )
    (fp_text user "Author: Antmicro" (at -0.932 4.17) (layer "F.Fab") hide
        (effects (font (size 0.7 0.7) (thickness 0.15)) (justify left bottom))
    )
    (fp_rect (start -0.94 -0.47) (end 0.94 0.47)
      (stroke (width 0.05) (type solid)) (fill none) (layer "F.CrtYd"))
    (fp_rect (start -0.499 -0.249) (end 0.499 0.249)
      (stroke (width 0.15) (type solid)) (fill none) (layer "F.Fab"))
    (pad "1" smd roundrect (at -0.484 0) (size 0.59 0.64) (layers "F.Cu" "F.Paste" "F.Mask") (roundrect_rratio 0.25)
      (net 412 "/FMC HPC/GTX_TX0_C_N") (pintype "passive"))
    (pad "2" smd roundrect (at 0.484 0) (size 0.59 0.64) (layers "F.Cu" "F.Paste" "F.Mask") (roundrect_rratio 0.25)
      (net 418 "GTX_TX0_N") (pintype "passive"))
  )
	(footprint "data-center-rdimm-ddr4-tester-footprints:R_0402_1005Metric" (layer "F.Cu")
    (at 238.3 122.8 -90)
    (descr "Resistor SMD 0402")
    (tags "resistor SMD 0402")
    (property "Author" "Antmicro")
    (property "DNP" "DNP")
    (property "License" "Apache-2.0")
    (property "MPN" "CR0402-FX-4702GLF")
    (property "Manufacturer" "Bourns")
    (property "Sheetfile" "supply.kicad_sch")
    (property "Sheetname" "Supply")
    (property "Tolerance" "1%")
    (property "Val" "47k")
    (property "dnp" "")
    (property "exclude_from_bom" "")
    (property "ki_description" "47k resistor in 0402 package with 1% tolerance")
    (attr exclude_from_pos_files exclude_from_bom)
    (fp_text reference "R118" (at -0.03 -1.32 -90) (layer "F.SilkS")
        (effects (font (size 0.7 0.7) (thickness 0.15)) (justify left bottom))
    )
    (fp_text value "R_47k_0402" (at 0 1.4 -90) (layer "F.Fab") hide
        (effects (font (size 0.7 0.7) (thickness 0.15)) (justify left bottom))
    )
    (fp_text user "${REFERENCE}" (at -0.95 3.168 -90) (layer "F.Fab") hide
        (effects (font (size 0.7 0.7) (thickness 0.15)) (justify left bottom))
    )
    (fp_text user "Author: Antmicro" (at -0.95 4.169 -90) (layer "F.Fab") hide
        (effects (font (size 0.7 0.7) (thickness 0.15)) (justify left bottom))
    )
    (fp_text user "License: Apache-2.0" (at -0.95 5.169 -90) (layer "F.Fab") hide
        (effects (font (size 0.7 0.7) (thickness 0.15)) (justify left bottom))
    )
    (fp_rect (start -0.93 -0.47) (end 0.93 0.47)
      (stroke (width 0.05) (type solid)) (fill none) (layer "F.CrtYd"))
    (fp_rect (start -0.5 -0.25) (end 0.5 0.25)
      (stroke (width 0.15) (type solid)) (fill none) (layer "F.Fab"))
    (pad "1" smd roundrect (at -0.485 0 270) (size 0.59 0.64) (layers "F.Cu" "F.Paste" "F.Mask") (roundrect_rratio 0.25)
      (net 864 "VIN_POE") (pintype "passive"))
    (pad "2" smd roundrect (at 0.485 0 270) (size 0.59 0.64) (layers "F.Cu" "F.Paste" "F.Mask") (roundrect_rratio 0.25)
      (net 108 "Net-(U27-~{OE})") (pintype "passive"))
  )
	(footprint "data-center-rdimm-ddr4-tester-footprints:mounting-hole-3mm-NPTH" (layer "F.Cu")
    (at 110 133)
    (property "Author" "Antmicro")
    (property "License" "Apache-2.0")
    (property "MPN" "")
    (property "Manufacturer" "")
    (property "Sheetfile" "data-center-rdimm-ddr4-tester.kicad_sch")
    (property "Sheetname" "")
    (attr through_hole)
    (fp_text reference "MP1" (at 0 -1.8) (layer "F.SilkS") hide
        (effects (font (size 0.7 0.7) (thickness 0.15)) (justify left bottom))
    )
    (fp_text value "PCB_Mount_Hole_3mm_NPTH" (at 0 2.3) (layer "F.Fab") hide
        (effects (font (size 0.7 0.7) (thickness 0.15)) (justify left bottom))
    )
    (fp_text user "Author: Antmicro" (at 0 5.95) (layer "F.Fab") hide
        (effects (font (size 0.7 0.7) (thickness 0.15)) (justify left bottom))
    )
    (fp_text user "License: Apache-2.0" (at 0 7.15) (layer "F.Fab") hide
        (effects (font (size 0.7 0.7) (thickness 0.15)) (justify left bottom))
    )
    (fp_text user "${REFERENCE}" (at 0 4.749) (layer "F.Fab") hide
        (effects (font (size 0.7 0.7) (thickness 0.15)) (justify left bottom))
    )
    (pad "" np_thru_hole circle (at 0 0) (size 3 3) (drill 3) (layers "*.Cu" "*.Mask"))
  )
)
